(kicad_pcb
	(version 20260206)
	(generator "pcbnew")
	(generator_version "10.0")
	(general
		(thickness 1.6)
		(legacy_teardrops no)
	)
	(paper "A4")
	(title_block
		(title "Bryce Canyon_IOM_IOC_16318-2_OCP.brd")
		(comment 1 "Bryce Canyon / footprints 280-286 of 1605")
	)
	(layers
		(0 "F.Cu" signal "TOP")
		(4 "In1.Cu" signal "L2GND")
		(6 "In2.Cu" signal "L3")
		(8 "In3.Cu" signal "L4VCC")
		(10 "In4.Cu" signal "L5VCC")
		(12 "In5.Cu" signal "L6")
		(14 "In6.Cu" signal "L7GND")
		(2 "B.Cu" signal "BOTTOM")
		(9 "F.Adhes" user "F.Adhesive")
		(11 "B.Adhes" user "B.Adhesive")
		(13 "F.Paste" user "Package Geometry/Pastemask Top")
		(15 "B.Paste" user "Package Geometry/Pastemask Bottom")
		(5 "F.SilkS" user "Ref Des/Silkscreen Top")
		(7 "B.SilkS" user "Ref Des/Silkscreen Bottom")
		(1 "F.Mask" user "Board Geometry/Soldermask Top")
		(3 "B.Mask" user "Board Geometry/Soldermask Bottom")
		(17 "Dwgs.User" user "User.Drawings")
		(19 "Cmts.User" user "User.Comments")
		(21 "Eco1.User" user "User.Eco1")
		(23 "Eco2.User" user "User.Eco2")
		(25 "Edge.Cuts" user "Board Geometry/Outline")
		(27 "Margin" user)
		(31 "F.CrtYd" user "Package Geometry/Place Bound Top")
		(29 "B.CrtYd" user "Package Geometry/Place Bound Bottom")
		(35 "F.Fab" user "Ref Des/Assembly Top")
		(33 "B.Fab" user "Ref Des/Assembly Bottom")
	)
	(footprint ""
		(layer "F.Cu")
		(at 211.6836 -111.5568 180)
		(property "Reference" "C324"
			(at 0 0 180)
			(layer "F.SilkS")
			(hide yes)
			(effects
				(font
					(size 1.27 1.27)
				)
			)
		)
		(property "Value" "SE470UF2VDM-GP"
			(at 0 -9.6012 180)
			(unlocked yes)
			(layer "F.Fab")
			(hide yes)
			(effects
				(font
					(size 1.016 1.016)
					(thickness 0.1524)
				)
			)
		)
		(property "Device Type" "CT7343H83"
			(at 0 -11.1252 180)
			(unlocked yes)
			(layer "F.Fab")
			(hide yes)
			(effects
				(font
					(size 1.016 1.016)
					(thickness 0.1524)
				)
			)
		)
		(duplicate_pad_numbers_are_jumpers no)
		(fp_line
			(start 2.286 4.8768)
			(end -2.286 4.8768)
			(stroke
				(width 0.1524)
				(type default)
			)
			(layer "F.SilkS")
		)
		(fp_line
			(start 2.286 2.032)
			(end 2.286 4.8768)
			(stroke
				(width 0.1524)
				(type default)
			)
			(layer "F.SilkS")
		)
		(fp_line
			(start 2.286 -2.032)
			(end 2.286 -4.8768)
			(stroke
				(width 0.1524)
				(type default)
			)
			(layer "F.SilkS")
		)
		(fp_line
			(start 2.286 -4.8768)
			(end -2.286 -4.8768)
			(stroke
				(width 0.1524)
				(type default)
			)
			(layer "F.SilkS")
		)
		(fp_line
			(start 2.1082 -4.699)
			(end -2.1082 -4.699)
			(stroke
				(width 0.508)
				(type default)
			)
			(layer "F.SilkS")
		)
		(fp_line
			(start -2.286 4.8768)
			(end -2.286 2.032)
			(stroke
				(width 0.1524)
				(type default)
			)
			(layer "F.SilkS")
		)
		(fp_line
			(start -2.286 -4.8768)
			(end -2.286 -2.032)
			(stroke
				(width 0.1524)
				(type default)
			)
			(layer "F.SilkS")
		)
		(fp_rect
			(start -2.1463 3.6449)
			(end 2.1463 -3.6449)
			(stroke
				(width 0)
				(type default)
			)
			(fill no)
			(layer "F.CrtYd")
		)
		(fp_poly
			(pts
				(xy -2.54 4.953) (xy -2.54 4.2926) (xy -3.81 4.2926) (xy -3.81 -4.2926) (xy -2.54 -4.2926) (xy -2.54 -4.953)
				(xy 2.54 -4.953) (xy 2.54 -4.2926) (xy 3.81 -4.2926) (xy 3.81 -1.6256) (xy 2.1463 -1.6256) (xy 2.1463 -3.6449)
				(xy -2.1463 -3.6449) (xy -2.1463 3.6449) (xy 2.1463 3.6449) (xy 2.1463 -1.6129) (xy 3.81 -1.6129)
				(xy 3.81 4.2926) (xy 2.54 4.2926) (xy 2.54 4.953)
			)
			(stroke
				(width 0)
				(type default)
			)
			(fill no)
			(layer "F.CrtYd")
		)
		(fp_rect
			(start 2.54 4.2926)
			(end 3.81 -4.2926)
			(stroke
				(width 0)
				(type default)
			)
			(fill no)
			(layer "F.Fab")
		)
		(fp_rect
			(start -2.54 4.953)
			(end 2.54 -4.953)
			(stroke
				(width 0)
				(type default)
			)
			(fill no)
			(layer "F.Fab")
		)
		(fp_rect
			(start -3.81 4.2926)
			(end -2.54 -4.2926)
			(stroke
				(width 0)
				(type default)
			)
			(fill no)
			(layer "F.Fab")
		)
		(pad "1" smd rect
			(at 0 -3.1496 180)
			(size 2.413 2.286)
			(layers "F.Cu" "F.Mask" "F.Paste")
			(net "P0V975")
		)
		(pad "2" smd rect
			(at 0 3.1496 180)
			(size 2.413 2.286)
			(layers "F.Cu" "F.Mask" "F.Paste")
			(net "GND")
		)
		(zone
			(layer "F.Cu")
			(hatch none 0.5)
			(connect_pads
				(clearance 0)
			)
			(min_thickness 0.25)
			(keepout
				(tracks allowed)
				(vias not_allowed)
				(pads allowed)
				(copperpour not_allowed)
				(footprints allowed)
			)
			(placement
				(enabled no)
				(sheetname "")
			)
			(fill
				(thermal_gap 0.5)
				(thermal_bridge_width 0.5)
				(island_removal_mode 0)
			)
			(polygon
				(pts
					(xy 210.1723 -109.8677) (xy 210.1723 -106.9594) (xy 213.1949 -106.9594) (xy 213.1949 -109.855)
					(xy 213.1949 -110.1852) (xy 210.1723 -110.1852)
				)
			)
		)
		(zone
			(layer "F.Cu")
			(hatch none 0.5)
			(connect_pads
				(clearance 0)
			)
			(min_thickness 0.25)
			(keepout
				(tracks allowed)
				(vias not_allowed)
				(pads allowed)
				(copperpour not_allowed)
				(footprints allowed)
			)
			(placement
				(enabled no)
				(sheetname "")
			)
			(fill
				(thermal_gap 0.5)
				(thermal_bridge_width 0.5)
				(island_removal_mode 0)
			)
			(polygon
				(pts
					(xy 213.1949 -116.1542) (xy 210.1723 -116.1542) (xy 210.1723 -113.2586) (xy 210.1723 -112.9284)
					(xy 213.1949 -112.9284) (xy 213.1949 -113.2586)
				)
			)
		)
	)
	(footprint ""
		(layer "F.Cu")
		(at 70.744842 -186.28487 180)
		(property "Reference" "C197"
			(at 0 0 180)
			(layer "F.SilkS")
			(hide yes)
			(effects
				(font
					(size 1.27 1.27)
				)
			)
		)
		(property "Value" "SC1U16V3KX-5GP"
			(at 0 -2.8194 180)
			(unlocked yes)
			(layer "F.Fab")
			(hide yes)
			(effects
				(font
					(size 1.016 1.016)
					(thickness 0.1524)
				)
			)
		)
		(property "Device Type" "C603H36"
			(at 0 -4.3434 180)
			(unlocked yes)
			(layer "F.Fab")
			(hide yes)
			(effects
				(font
					(size 1.016 1.016)
					(thickness 0.1524)
				)
			)
		)
		(duplicate_pad_numbers_are_jumpers no)
		(fp_line
			(start 0.508 0)
			(end -0.508 0)
			(stroke
				(width 0.2032)
				(type default)
			)
			(layer "F.SilkS")
		)
		(fp_rect
			(start -0.5842 1.3335)
			(end 0.5842 -1.3335)
			(stroke
				(width 0)
				(type default)
			)
			(fill no)
			(layer "F.CrtYd")
		)
		(fp_rect
			(start -0.5842 1.3335)
			(end 0.5842 -1.3335)
			(stroke
				(width 0)
				(type default)
			)
			(fill no)
			(layer "F.Fab")
		)
		(pad "1" smd custom
			(at 0 -0.762 180)
			(size 0.2159 0.2159)
			(layers "F.Cu" "F.Mask" "F.Paste")
			(net "TPS74801_P2V5_STBY_BIAS")
			(options
				(clearance outline)
				(anchor circle)
			)
			(primitives
				(gr_poly
					(pts
						(arc
							(start -0.3302 -0.4318)
							(mid -0.402042 -0.402042)
							(end -0.4318 -0.3302)
						)
						(arc
							(start -0.4318 0.3302)
							(mid -0.402042 0.402042)
							(end -0.3302 0.4318)
						)
						(arc
							(start 0.3302 0.4318)
							(mid 0.402042 0.402042)
							(end 0.4318 0.3302)
						)
						(arc
							(start 0.4318 -0.3302)
							(mid 0.402042 -0.402042)
							(end 0.3302 -0.4318)
						)
					)
					(width 0)
					(fill yes)
				)
			)
		)
		(pad "2" smd custom
			(at 0 0.762 180)
			(size 0.2159 0.2159)
			(layers "F.Cu" "F.Mask" "F.Paste")
			(net "GND")
			(options
				(clearance outline)
				(anchor circle)
			)
			(primitives
				(gr_poly
					(pts
						(arc
							(start -0.3302 -0.4318)
							(mid -0.402042 -0.402042)
							(end -0.4318 -0.3302)
						)
						(arc
							(start -0.4318 0.3302)
							(mid -0.402042 0.402042)
							(end -0.3302 0.4318)
						)
						(arc
							(start 0.3302 0.4318)
							(mid 0.402042 0.402042)
							(end 0.4318 0.3302)
						)
						(arc
							(start 0.4318 -0.3302)
							(mid 0.402042 -0.402042)
							(end 0.3302 -0.4318)
						)
					)
					(width 0)
					(fill yes)
				)
			)
		)
	)
	(footprint ""
		(layer "F.Cu")
		(at 35.235896 -136.73709 90)
		(property "Reference" "R351"
			(at 0 0 90)
			(layer "F.SilkS")
			(hide yes)
			(effects
				(font
					(size 1.27 1.27)
				)
			)
		)
		(property "Value" "10KR2F-2-GP"
			(at 0.064008 -3.993896 90)
			(unlocked yes)
			(layer "F.Fab")
			(hide yes)
			(effects
				(font
					(size 1.016 1.016)
					(thickness 0.1524)
				)
			)
		)
		(property "Device Type" "R402H16"
			(at 0.064008 -5.517896 90)
			(unlocked yes)
			(layer "F.Fab")
			(hide yes)
			(effects
				(font
					(size 1.016 1.016)
					(thickness 0.1524)
				)
			)
		)
		(duplicate_pad_numbers_are_jumpers no)
		(fp_line
			(start 0.508 -0.9398)
			(end -0.508 -0.9398)
			(stroke
				(width 0.1524)
				(type default)
			)
			(layer "F.SilkS")
		)
		(fp_line
			(start -0.508 -0.9398)
			(end -0.508 0.9398)
			(stroke
				(width 0.1524)
				(type default)
			)
			(layer "F.SilkS")
		)
		(fp_rect
			(start -0.508 0.9398)
			(end 0.508 -0.9398)
			(stroke
				(width 0)
				(type default)
			)
			(fill no)
			(layer "F.CrtYd")
		)
		(fp_rect
			(start -0.508 0.9398)
			(end 0.508 -0.9398)
			(stroke
				(width 0)
				(type default)
			)
			(fill no)
			(layer "F.Fab")
		)
		(pad "1" smd custom
			(at 0 -0.4445 90)
			(size 0.1397 0.1397)
			(layers "F.Cu" "F.Mask" "F.Paste")
			(net "GND")
			(options
				(clearance outline)
				(anchor circle)
			)
			(primitives
				(gr_poly
					(pts
						(arc
							(start -0.1778 -0.2794)
							(mid -0.249642 -0.249642)
							(end -0.2794 -0.1778)
						)
						(arc
							(start -0.2794 0.1778)
							(mid -0.249642 0.249642)
							(end -0.1778 0.2794)
						)
						(arc
							(start 0.1778 0.2794)
							(mid 0.249642 0.249642)
							(end 0.2794 0.1778)
						)
						(arc
							(start 0.2794 -0.1778)
							(mid 0.249642 -0.249642)
							(end 0.1778 -0.2794)
						)
					)
					(width 0)
					(fill yes)
				)
			)
		)
		(pad "2" smd custom
			(at 0 0.4445 90)
			(size 0.1397 0.1397)
			(layers "F.Cu" "F.Mask" "F.Paste")
			(net "PECI")
			(options
				(clearance outline)
				(anchor circle)
			)
			(primitives
				(gr_poly
					(pts
						(arc
							(start -0.1778 -0.2794)
							(mid -0.249642 -0.249642)
							(end -0.2794 -0.1778)
						)
						(arc
							(start -0.2794 0.1778)
							(mid -0.249642 0.249642)
							(end -0.1778 0.2794)
						)
						(arc
							(start 0.1778 0.2794)
							(mid 0.249642 0.249642)
							(end 0.2794 0.1778)
						)
						(arc
							(start 0.2794 -0.1778)
							(mid 0.249642 -0.249642)
							(end 0.1778 -0.2794)
						)
					)
					(width 0)
					(fill yes)
				)
			)
		)
	)
	(footprint ""
		(layer "F.Cu")
		(at 156.723842 -95.03791 180)
		(property "Reference" "C484"
			(at 0 0 180)
			(layer "F.SilkS")
			(hide yes)
			(effects
				(font
					(size 1.27 1.27)
				)
			)
		)
		(property "Value" "SCD1U16V2KX-3GP"
			(at 1.1811 -2.7051 180)
			(unlocked yes)
			(layer "F.Fab")
			(hide yes)
			(effects
				(font
					(size 1.016 1.016)
					(thickness 0.1524)
				)
			)
		)
		(property "Device Type" "C402H22"
			(at 1.1811 -4.2291 180)
			(unlocked yes)
			(layer "F.Fab")
			(hide yes)
			(effects
				(font
					(size 1.016 1.016)
					(thickness 0.1524)
				)
			)
		)
		(duplicate_pad_numbers_are_jumpers no)
		(fp_rect
			(start -0.4318 0.9525)
			(end 0.4318 -0.9525)
			(stroke
				(width 0)
				(type default)
			)
			(fill no)
			(layer "F.CrtYd")
		)
		(fp_rect
			(start -0.4318 0.9525)
			(end 0.4318 -0.9525)
			(stroke
				(width 0)
				(type default)
			)
			(fill no)
			(layer "F.Fab")
		)
		(pad "1" smd custom
			(at 0 -0.4445 180)
			(size 0.1524 0.1524)
			(layers "F.Cu" "F.Mask" "F.Paste")
			(net "P3V3")
			(options
				(clearance outline)
				(anchor circle)
			)
			(primitives
				(gr_poly
					(pts
						(arc
							(start 0.3048 -0.2032)
							(mid 0.275042 -0.275042)
							(end 0.2032 -0.3048)
						)
						(arc
							(start -0.2032 -0.3048)
							(mid -0.275042 -0.275042)
							(end -0.3048 -0.2032)
						)
						(arc
							(start -0.3048 0.2032)
							(mid -0.275042 0.275042)
							(end -0.2032 0.3048)
						)
						(arc
							(start 0.2032 0.3048)
							(mid 0.275042 0.275042)
							(end 0.3048 0.2032)
						)
					)
					(width 0)
					(fill yes)
				)
			)
		)
		(pad "2" smd custom
			(at 0 0.4445 180)
			(size 0.1524 0.1524)
			(layers "F.Cu" "F.Mask" "F.Paste")
			(net "GND")
			(options
				(clearance outline)
				(anchor circle)
			)
			(primitives
				(gr_poly
					(pts
						(arc
							(start 0.3048 -0.2032)
							(mid 0.275042 -0.275042)
							(end 0.2032 -0.3048)
						)
						(arc
							(start -0.2032 -0.3048)
							(mid -0.275042 -0.275042)
							(end -0.3048 -0.2032)
						)
						(arc
							(start -0.3048 0.2032)
							(mid -0.275042 0.275042)
							(end -0.2032 0.3048)
						)
						(arc
							(start 0.2032 0.3048)
							(mid 0.275042 0.275042)
							(end 0.3048 0.2032)
						)
					)
					(width 0)
					(fill yes)
				)
			)
		)
	)
	(footprint ""
		(layer "F.Cu")
		(at 79.172816 -181.33568)
		(property "Reference" "C198"
			(at 0 0 0)
			(layer "F.SilkS")
			(hide yes)
			(effects
				(font
					(size 1.27 1.27)
				)
			)
		)
		(property "Value" "SCD1U16V2KX-3GP"
			(at 1.1811 -2.7051 0)
			(unlocked yes)
			(layer "F.Fab")
			(hide yes)
			(effects
				(font
					(size 1.016 1.016)
					(thickness 0.1524)
				)
			)
		)
		(property "Device Type" "C402H22"
			(at 1.1811 -4.2291 0)
			(unlocked yes)
			(layer "F.Fab")
			(hide yes)
			(effects
				(font
					(size 1.016 1.016)
					(thickness 0.1524)
				)
			)
		)
		(duplicate_pad_numbers_are_jumpers no)
		(fp_rect
			(start -0.4318 0.9525)
			(end 0.4318 -0.9525)
			(stroke
				(width 0)
				(type default)
			)
			(fill no)
			(layer "F.CrtYd")
		)
		(fp_rect
			(start -0.4318 0.9525)
			(end 0.4318 -0.9525)
			(stroke
				(width 0)
				(type default)
			)
			(fill no)
			(layer "F.Fab")
		)
		(pad "1" smd custom
			(at 0 -0.4445)
			(size 0.1524 0.1524)
			(layers "F.Cu" "F.Mask" "F.Paste")
			(net "P3V3_STBY")
			(options
				(clearance outline)
				(anchor circle)
			)
			(primitives
				(gr_poly
					(pts
						(arc
							(start 0.3048 -0.2032)
							(mid 0.275042 -0.275042)
							(end 0.2032 -0.3048)
						)
						(arc
							(start -0.2032 -0.3048)
							(mid -0.275042 -0.275042)
							(end -0.3048 -0.2032)
						)
						(arc
							(start -0.3048 0.2032)
							(mid -0.275042 0.275042)
							(end -0.2032 0.3048)
						)
						(arc
							(start 0.2032 0.3048)
							(mid 0.275042 0.275042)
							(end 0.3048 0.2032)
						)
					)
					(width 0)
					(fill yes)
				)
			)
		)
		(pad "2" smd custom
			(at 0 0.4445)
			(size 0.1524 0.1524)
			(layers "F.Cu" "F.Mask" "F.Paste")
			(net "GND")
			(options
				(clearance outline)
				(anchor circle)
			)
			(primitives
				(gr_poly
					(pts
						(arc
							(start 0.3048 -0.2032)
							(mid 0.275042 -0.275042)
							(end 0.2032 -0.3048)
						)
						(arc
							(start -0.2032 -0.3048)
							(mid -0.275042 -0.275042)
							(end -0.3048 -0.2032)
						)
						(arc
							(start -0.3048 0.2032)
							(mid -0.275042 0.275042)
							(end -0.2032 0.3048)
						)
						(arc
							(start 0.2032 0.3048)
							(mid 0.275042 0.275042)
							(end 0.3048 0.2032)
						)
					)
					(width 0)
					(fill yes)
				)
			)
		)
	)
	(footprint ""
		(layer "F.Cu")
		(at 91.818968 -59.111896 90)
		(property "Reference" "D4"
			(at 0 0 90)
			(layer "F.SilkS")
			(hide yes)
			(effects
				(font
					(size 1.27 1.27)
				)
			)
		)
		(property "Value" "SMF15A-GP"
			(at -2.0955 1.2192 90)
			(unlocked yes)
			(layer "F.Fab")
			(hide yes)
			(effects
				(font
					(size 1.016 1.016)
					(thickness 0.1524)
				)
			)
		)
		(property "Device Type" "SOD123AK-2H43"
			(at -2.0955 -0.3048 90)
			(unlocked yes)
			(layer "F.Fab")
			(hide yes)
			(effects
				(font
					(size 1.016 1.016)
					(thickness 0.1524)
				)
			)
		)
		(duplicate_pad_numbers_are_jumpers no)
		(fp_line
			(start 1.1557 -2.7686)
			(end -1.1557 -2.7686)
			(stroke
				(width 0.1524)
				(type default)
			)
			(layer "F.SilkS")
		)
		(fp_line
			(start -1.1557 -2.7686)
			(end -1.1557 2.7686)
			(stroke
				(width 0.1524)
				(type default)
			)
			(layer "F.SilkS")
		)
		(fp_line
			(start 1.1557 2.7686)
			(end 1.1557 -2.7686)
			(stroke
				(width 0.1524)
				(type default)
			)
			(layer "F.SilkS")
		)
		(fp_line
			(start -1.1557 2.7686)
			(end 1.1557 2.7686)
			(stroke
				(width 0.1524)
				(type default)
			)
			(layer "F.SilkS")
		)
		(fp_line
			(start 1.1557 2.921)
			(end -1.1557 2.921)
			(stroke
				(width 0.508)
				(type default)
			)
			(layer "F.SilkS")
		)
		(fp_poly
			(pts
				(xy -0.4572 1.8669) (xy -0.4572 1.397) (xy -0.9017 1.397) (xy -0.9017 -1.397) (xy -0.4572 -1.397)
				(xy -0.4572 -1.8669) (xy 0.4572 -1.8669) (xy 0.4572 -1.397) (xy 0.9017 -1.397) (xy 0.9017 1.397)
				(xy 0.4572 1.397) (xy 0.4572 1.8669)
			)
			(stroke
				(width 0)
				(type default)
			)
			(fill no)
			(layer "F.CrtYd")
		)
		(fp_poly
			(pts
				(xy -1.4097 2.8448) (xy -1.4097 -2.8448) (xy 1.4097 -2.8448) (xy 1.4097 1.3716) (xy 0.9017 1.3716)
				(xy 0.9017 -1.397) (xy 0.4572 -1.397) (xy 0.4572 -1.8669) (xy -0.4572 -1.8669) (xy -0.4572 -1.397)
				(xy -0.9017 -1.397) (xy -0.9017 1.397) (xy -0.4572 1.397) (xy -0.4572 1.8669) (xy 0.4572 1.8669)
				(xy 0.4572 1.397) (xy 0.9017 1.397) (xy 0.9017 1.3843) (xy 1.4097 1.3843) (xy 1.4097 2.8448)
			)
			(stroke
				(width 0)
				(type default)
			)
			(fill no)
			(layer "F.CrtYd")
		)
		(fp_rect
			(start -1.4097 2.8448)
			(end 1.4097 -2.8448)
			(stroke
				(width 0)
				(type default)
			)
			(fill no)
			(layer "F.Fab")
		)
		(pad "A" smd rect
			(at 0 -1.75768 90)
			(size 1.143 1.4986)
			(layers "F.Cu" "F.Mask" "F.Paste")
			(net "P3V3_EN_R")
		)
		(pad "K" smd rect
			(at 0 1.75768 90)
			(size 1.143 1.4986)
			(layers "F.Cu" "F.Mask" "F.Paste")
			(net "P3V3_EN")
		)
	)
	(footprint ""
		(layer "F.Cu")
		(at 61.8236 -162.8648 180)
		(property "Reference" "R72"
			(at 0 0 180)
			(layer "F.SilkS")
			(hide yes)
			(effects
				(font
					(size 1.27 1.27)
				)
			)
		)
		(property "Value" "10KR2F-2-GP"
			(at 0.064008 -3.993896 180)
			(unlocked yes)
			(layer "F.Fab")
			(hide yes)
			(effects
				(font
					(size 1.016 1.016)
					(thickness 0.1524)
				)
			)
		)
		(property "Device Type" "R402H16"
			(at 0.064008 -5.517896 180)
			(unlocked yes)
			(layer "F.Fab")
			(hide yes)
			(effects
				(font
					(size 1.016 1.016)
					(thickness 0.1524)
				)
			)
		)
		(duplicate_pad_numbers_are_jumpers no)
		(fp_line
			(start 0.508 -0.9398)
			(end -0.508 -0.9398)
			(stroke
				(width 0.1524)
				(type default)
			)
			(layer "F.SilkS")
		)
		(fp_line
			(start -0.508 -0.9398)
			(end -0.508 0.9398)
			(stroke
				(width 0.1524)
				(type default)
			)
			(layer "F.SilkS")
		)
		(fp_rect
			(start -0.508 0.9398)
			(end 0.508 -0.9398)
			(stroke
				(width 0)
				(type default)
			)
			(fill no)
			(layer "F.CrtYd")
		)
		(fp_rect
			(start -0.508 0.9398)
			(end 0.508 -0.9398)
			(stroke
				(width 0)
				(type default)
			)
			(fill no)
			(layer "F.Fab")
		)
		(pad "1" smd custom
			(at 0 -0.4445 180)
			(size 0.1397 0.1397)
			(layers "F.Cu" "F.Mask" "F.Paste")
			(net "P3V3_STBY")
			(options
				(clearance outline)
				(anchor circle)
			)
			(primitives
				(gr_poly
					(pts
						(arc
							(start -0.1778 -0.2794)
							(mid -0.249642 -0.249642)
							(end -0.2794 -0.1778)
						)
						(arc
							(start -0.2794 0.1778)
							(mid -0.249642 0.249642)
							(end -0.1778 0.2794)
						)
						(arc
							(start 0.1778 0.2794)
							(mid 0.249642 0.249642)
							(end 0.2794 0.1778)
						)
						(arc
							(start 0.2794 -0.1778)
							(mid 0.249642 -0.249642)
							(end 0.1778 -0.2794)
						)
					)
					(width 0)
					(fill yes)
				)
			)
		)
		(pad "2" smd custom
			(at 0 0.4445 180)
			(size 0.1397 0.1397)
			(layers "F.Cu" "F.Mask" "F.Paste")
			(net "FM_TPM_PRSNT_RST")
			(options
				(clearance outline)
				(anchor circle)
			)
			(primitives
				(gr_poly
					(pts
						(arc
							(start -0.1778 -0.2794)
							(mid -0.249642 -0.249642)
							(end -0.2794 -0.1778)
						)
						(arc
							(start -0.2794 0.1778)
							(mid -0.249642 0.249642)
							(end -0.1778 0.2794)
						)
						(arc
							(start 0.1778 0.2794)
							(mid 0.249642 0.249642)
							(end 0.2794 0.1778)
						)
						(arc
							(start 0.2794 -0.1778)
							(mid 0.249642 -0.249642)
							(end 0.1778 -0.2794)
						)
					)
					(width 0)
					(fill yes)
				)
			)
		)
	)
)
